FILE_TYPE = MULTI_PHYS_TABLE;

PART '74LVC1G17GW'

{========================================================================================}
:VALUE         | PART_TYPE | MATERIAL | PART_NUMBER       = STANDARD | LIFECYCLE      | PART_NUMBER       | JEDEC_TYPE | DESCRIPTION                             | MANUFTR | MANUF_PN      | RD_CMPLS_LVL | CMPLS_LVL | FROM_PJ      | CLASS | DIP_SMD | DATA                | EE_CHECK_LIST    | FP_ECN | PSL | CREATOR | STATUS | CREATEDAY  ;
{========================================================================================}
 '74LVC1G17GW' | 'SMLF'    | 'IC'     | 'AL1G0017K01'(!)  = ''       | ''             | 'AL1G0017K01'     |'TSSOP5'| 'IC OTHER(5P) 74LVC1G17GW(TSSOP)'       | 'NXP'   | '74LVC1G17GW' | 'EP(V1)'     | 'EP(V1)'  | 'MF1-EUPHIE' | 'IC'  | ''      | 'NXP_74LVC1G17.pdf' | ''               | ''     | ''  | ''      | ''     | '20140828'
 '74LVC1G17GW' | 'SMLF'    | 'EMPTY'  | 'AL1G0017K01'(!)  = ''       | ''             | 'AL1G0017K01'     |'TSSOP5'| 'IC OTHER(5P) 74LVC1G17GW(TSSOP)'       | 'NXP'   | '74LVC1G17GW' | 'EP(V1)'     | 'EP(V1)'  | 'MF1-EUPHIE' | 'IC'  | ''      | 'NXP_74LVC1G17.pdf' | ''               | ''     | ''  | ''      | ''     | '20140828'
 '74LVC1G17GW' | 'SMLF'    | 'IC'     | 'AL1G0017K01SEL1'(!) = ''       | ''               | 'AL1G0017K01SEL1' |'TSSOP5'| 'IC OTHER(5P) 74LVC1G17GW(TSSOP)SELASN' | 'NXP'   | '74LVC1G17GW' | 'EP(V1)'     | 'EP(V1)'  | 'MF1-EUPHIE' | 'IC'  | ''      | 'NXP_74LVC1G17.pdf' | 'SEL_15QPN.xlsx' | ''     | ''  | ''      | ''     | '20230726'
 '74LVC1G17GW' | 'SMLF'    | 'EMPTY'  | 'AL1G0017K01SEL1'(!) = ''       | ''               | 'AL1G0017K01SEL1' |'TSSOP5'| 'IC OTHER(5P) 74LVC1G17GW(TSSOP)SELASN' | 'NXP'   | '74LVC1G17GW' | 'EP(V1)'     | 'EP(V1)'  | 'MF1-EUPHIE' | 'IC'  | ''      | 'NXP_74LVC1G17.pdf' | 'SEL_15QPN.xlsx' | ''     | ''  | ''      | ''     | '20230726'

END_PART

END.

